(kicad_pcb
	(version 20260206)
	(generator "pcbnew")
	(generator_version "10.0")
	(general
		(thickness 1.6)
		(legacy_teardrops no)
	)
	(paper "A4")
	(title_block
		(title "01162023_DA0F0TEBIF0_F0T_Expander_BD_F_brd_V02_OCP.brd")
		(comment 1 "Grand Teton / footprints 9183-9189 of 9728")
	)
	(layers
		(0 "F.Cu" signal "TOP")
		(4 "In1.Cu" signal "GND")
		(6 "In2.Cu" signal "VCC")
		(8 "In3.Cu" signal "VCC1")
		(10 "In4.Cu" signal "GND1")
		(12 "In5.Cu" signal "IN1")
		(14 "In6.Cu" signal "GND2")
		(16 "In7.Cu" signal "IN2")
		(18 "In8.Cu" signal "GND3")
		(20 "In9.Cu" signal "IN3")
		(22 "In10.Cu" signal "GND4")
		(24 "In11.Cu" signal "IN4")
		(26 "In12.Cu" signal "GND5")
		(28 "In13.Cu" signal "IN5")
		(30 "In14.Cu" signal "GND6")
		(32 "In15.Cu" signal "IN6")
		(34 "In16.Cu" signal "GND7")
		(2 "B.Cu" signal "BOTTOM")
		(9 "F.Adhes" user "F.Adhesive")
		(11 "B.Adhes" user "B.Adhesive")
		(13 "F.Paste" user "Package Geometry/Pastemask Top")
		(15 "B.Paste" user "Package Geometry/Pastemask Bottom")
		(5 "F.SilkS" user "Ref Des/Silkscreen Top")
		(7 "B.SilkS" user "Ref Des/Silkscreen Bottom")
		(1 "F.Mask" user "Board Geometry/Soldermask Top")
		(3 "B.Mask" user "Board Geometry/Soldermask Bottom")
		(17 "Dwgs.User" user "User.Drawings")
		(19 "Cmts.User" user "User.Comments")
		(21 "Eco1.User" user "User.Eco1")
		(23 "Eco2.User" user "User.Eco2")
		(25 "Edge.Cuts" user "Board Geometry/Outline")
		(27 "Margin" user)
		(31 "F.CrtYd" user "Package Geometry/Place Bound Top")
		(29 "B.CrtYd" user "Package Geometry/Place Bound Bottom")
		(35 "F.Fab" user "Ref Des/Assembly Top")
		(33 "B.Fab" user "Ref Des/Assembly Bottom")
	)
	(footprint ""
		(layer "B.Cu")
		(at 263.78408 -366.927384 180)
		(property "Reference" "PR6611"
			(at 0 0 0)
			(layer "B.SilkS")
			(hide yes)
			(effects
				(font
					(size 1.27 1.27)
				)
				(justify mirror)
			)
		)
		(property "Value" ""
			(at 0 0 0)
			(layer "B.Fab")
			(effects
				(font
					(size 1.27 1.27)
				)
				(justify mirror)
			)
		)
		(duplicate_pad_numbers_are_jumpers no)
		(fp_line
			(start 0.7874 0.4064)
			(end 0.7874 -0.4064)
			(stroke
				(width 0.1524)
				(type default)
			)
			(layer "B.SilkS")
		)
		(fp_line
			(start 0.7874 -0.4064)
			(end -0.7874 -0.4064)
			(stroke
				(width 0.1524)
				(type default)
			)
			(layer "B.SilkS")
		)
		(fp_line
			(start -0.7874 0.4064)
			(end 0.7874 0.4064)
			(stroke
				(width 0.1524)
				(type default)
			)
			(layer "B.SilkS")
		)
		(fp_line
			(start -0.7874 -0.4064)
			(end -0.7874 0.4064)
			(stroke
				(width 0.1524)
				(type default)
			)
			(layer "B.SilkS")
		)
		(fp_line
			(start 0.67945 0.3048)
			(end 0.67945 -0.305054)
			(stroke
				(width 0.1)
				(type default)
			)
			(layer "B.Fab")
		)
		(fp_line
			(start 0.67945 -0.305054)
			(end 0.12065 -0.305054)
			(stroke
				(width 0.1)
				(type default)
			)
			(layer "B.Fab")
		)
		(fp_line
			(start 0.12065 0.3048)
			(end 0.67945 0.3048)
			(stroke
				(width 0.1)
				(type default)
			)
			(layer "B.Fab")
		)
		(fp_line
			(start 0.12065 0.2794)
			(end 0.12065 0.3048)
			(stroke
				(width 0.1)
				(type default)
			)
			(layer "B.Fab")
		)
		(fp_line
			(start 0.12065 -0.2794)
			(end -0.12065 -0.2794)
			(stroke
				(width 0.1)
				(type default)
			)
			(layer "B.Fab")
		)
		(fp_line
			(start 0.12065 -0.305054)
			(end 0.12065 -0.2794)
			(stroke
				(width 0.1)
				(type default)
			)
			(layer "B.Fab")
		)
		(fp_line
			(start -0.120396 0.3048)
			(end -0.120396 0.2794)
			(stroke
				(width 0.1)
				(type default)
			)
			(layer "B.Fab")
		)
		(fp_line
			(start -0.120396 0.2794)
			(end 0.12065 0.2794)
			(stroke
				(width 0.1)
				(type default)
			)
			(layer "B.Fab")
		)
		(fp_line
			(start -0.12065 -0.2794)
			(end -0.12065 -0.3048)
			(stroke
				(width 0.1)
				(type default)
			)
			(layer "B.Fab")
		)
		(fp_line
			(start -0.12065 -0.3048)
			(end -0.67945 -0.3048)
			(stroke
				(width 0.1)
				(type default)
			)
			(layer "B.Fab")
		)
		(fp_line
			(start -0.67945 0.3048)
			(end -0.120396 0.3048)
			(stroke
				(width 0.1)
				(type default)
			)
			(layer "B.Fab")
		)
		(fp_line
			(start -0.67945 -0.3048)
			(end -0.67945 0.3048)
			(stroke
				(width 0.1)
				(type default)
			)
			(layer "B.Fab")
		)
		(pad "1" smd circle
			(at 0.40005 0)
			(size 0 0)
			(layers "B.Cu" "B.Mask" "B.Paste")
			(net "P12V_HSC_GATE2")
		)
		(pad "2" smd circle
			(at -0.40005 0)
			(size 0 0)
			(layers "B.Cu" "B.Mask" "B.Paste")
			(net "HS_GATE2_R_4")
		)
	)
	(footprint ""
		(layer "B.Cu")
		(at 281.755342 -157.0736 180)
		(property "Reference" "R205"
			(at 0 0 0)
			(layer "B.SilkS")
			(hide yes)
			(effects
				(font
					(size 1.27 1.27)
				)
				(justify mirror)
			)
		)
		(property "Value" ""
			(at 0 0 0)
			(layer "B.Fab")
			(effects
				(font
					(size 1.27 1.27)
				)
				(justify mirror)
			)
		)
		(duplicate_pad_numbers_are_jumpers no)
		(fp_line
			(start 0.7874 0.4064)
			(end 0.7874 -0.4064)
			(stroke
				(width 0.1524)
				(type default)
			)
			(layer "B.SilkS")
		)
		(fp_line
			(start 0.7874 -0.4064)
			(end -0.7874 -0.4064)
			(stroke
				(width 0.1524)
				(type default)
			)
			(layer "B.SilkS")
		)
		(fp_line
			(start -0.7874 0.4064)
			(end 0.7874 0.4064)
			(stroke
				(width 0.1524)
				(type default)
			)
			(layer "B.SilkS")
		)
		(fp_line
			(start -0.7874 -0.4064)
			(end -0.7874 0.4064)
			(stroke
				(width 0.1524)
				(type default)
			)
			(layer "B.SilkS")
		)
		(fp_line
			(start 0.67945 0.3048)
			(end 0.67945 -0.305054)
			(stroke
				(width 0.1)
				(type default)
			)
			(layer "B.Fab")
		)
		(fp_line
			(start 0.67945 -0.305054)
			(end 0.12065 -0.305054)
			(stroke
				(width 0.1)
				(type default)
			)
			(layer "B.Fab")
		)
		(fp_line
			(start 0.12065 0.3048)
			(end 0.67945 0.3048)
			(stroke
				(width 0.1)
				(type default)
			)
			(layer "B.Fab")
		)
		(fp_line
			(start 0.12065 0.2794)
			(end 0.12065 0.3048)
			(stroke
				(width 0.1)
				(type default)
			)
			(layer "B.Fab")
		)
		(fp_line
			(start 0.12065 -0.2794)
			(end -0.12065 -0.2794)
			(stroke
				(width 0.1)
				(type default)
			)
			(layer "B.Fab")
		)
		(fp_line
			(start 0.12065 -0.305054)
			(end 0.12065 -0.2794)
			(stroke
				(width 0.1)
				(type default)
			)
			(layer "B.Fab")
		)
		(fp_line
			(start -0.120396 0.3048)
			(end -0.120396 0.2794)
			(stroke
				(width 0.1)
				(type default)
			)
			(layer "B.Fab")
		)
		(fp_line
			(start -0.120396 0.2794)
			(end 0.12065 0.2794)
			(stroke
				(width 0.1)
				(type default)
			)
			(layer "B.Fab")
		)
		(fp_line
			(start -0.12065 -0.2794)
			(end -0.12065 -0.3048)
			(stroke
				(width 0.1)
				(type default)
			)
			(layer "B.Fab")
		)
		(fp_line
			(start -0.12065 -0.3048)
			(end -0.67945 -0.3048)
			(stroke
				(width 0.1)
				(type default)
			)
			(layer "B.Fab")
		)
		(fp_line
			(start -0.67945 0.3048)
			(end -0.120396 0.3048)
			(stroke
				(width 0.1)
				(type default)
			)
			(layer "B.Fab")
		)
		(fp_line
			(start -0.67945 -0.3048)
			(end -0.67945 0.3048)
			(stroke
				(width 0.1)
				(type default)
			)
			(layer "B.Fab")
		)
		(pad "1" smd circle
			(at 0.40005 0)
			(size 0 0)
			(layers "B.Cu" "B.Mask" "B.Paste")
			(net "NIC4_RBT_ARB_OUT")
		)
		(pad "2" smd circle
			(at -0.40005 0)
			(size 0 0)
			(layers "B.Cu" "B.Mask" "B.Paste")
			(net "NIC4_RBT_ARB_IN")
		)
	)
	(footprint ""
		(layer "B.Cu")
		(at 342.09355 -220.38691 90)
		(property "Reference" "C2070"
			(at 0 0 90)
			(layer "B.SilkS")
			(hide yes)
			(effects
				(font
					(size 1.27 1.27)
				)
				(justify mirror)
			)
		)
		(property "Value" ""
			(at 0 0 90)
			(layer "B.Fab")
			(effects
				(font
					(size 1.27 1.27)
				)
				(justify mirror)
			)
		)
		(duplicate_pad_numbers_are_jumpers no)
		(fp_line
			(start 0.69215 -0.2921)
			(end -0.69215 -0.2921)
			(stroke
				(width 0.1524)
				(type default)
			)
			(layer "B.SilkS")
		)
		(fp_line
			(start -0.69215 -0.2921)
			(end -0.69215 0.2921)
			(stroke
				(width 0.1524)
				(type default)
			)
			(layer "B.SilkS")
		)
		(fp_line
			(start 0.69215 0.2921)
			(end 0.69215 -0.2921)
			(stroke
				(width 0.1524)
				(type default)
			)
			(layer "B.SilkS")
		)
		(fp_line
			(start -0.69215 0.2921)
			(end 0.69215 0.2921)
			(stroke
				(width 0.1524)
				(type default)
			)
			(layer "B.SilkS")
		)
		(fp_line
			(start 0.51435 -0.2794)
			(end -0.51435 -0.2794)
			(stroke
				(width 0.1)
				(type default)
			)
			(layer "B.Fab")
		)
		(fp_line
			(start -0.51435 -0.2794)
			(end -0.51435 0.2794)
			(stroke
				(width 0.1)
				(type default)
			)
			(layer "B.Fab")
		)
		(fp_line
			(start 0.51435 0.2794)
			(end 0.51435 -0.2794)
			(stroke
				(width 0.1)
				(type default)
			)
			(layer "B.Fab")
		)
		(fp_line
			(start -0.51435 0.2794)
			(end 0.51435 0.2794)
			(stroke
				(width 0.1)
				(type default)
			)
			(layer "B.Fab")
		)
		(pad "1" smd circle
			(at 0.40005 0 270)
			(size 0 0)
			(layers "B.Cu" "B.Mask" "B.Paste")
			(net "P3V3_VCC_FPGA_CORE")
		)
		(pad "2" smd circle
			(at -0.40005 0 270)
			(size 0 0)
			(layers "B.Cu" "B.Mask" "B.Paste")
			(net "GND")
		)
		(zone
			(layer "B.Cu")
			(hatch none 0.5)
			(connect_pads
				(clearance 0)
			)
			(min_thickness 0.25)
			(keepout
				(tracks not_allowed)
				(vias allowed)
				(pads allowed)
				(copperpour not_allowed)
				(footprints allowed)
			)
			(placement
				(enabled no)
				(sheetname "")
			)
			(fill
				(thermal_gap 0.5)
				(thermal_bridge_width 0.5)
				(island_removal_mode 0)
			)
			(polygon
				(pts
					(xy 342.18118 -220.57741) (xy 342.239346 -220.48597) (xy 342.239346 -220.28658) (xy 342.18118 -220.19641)
					(xy 342.00592 -220.19641) (xy 341.9475 -220.28658) (xy 341.9475 -220.48597) (xy 342.005666 -220.57741)
				)
			)
		)
	)
	(footprint ""
		(layer "B.Cu")
		(at 372.38305 -220.932756 90)
		(property "Reference" "R3498"
			(at 0 0 90)
			(layer "B.SilkS")
			(hide yes)
			(effects
				(font
					(size 1.27 1.27)
				)
				(justify mirror)
			)
		)
		(property "Value" ""
			(at 0 0 90)
			(layer "B.Fab")
			(effects
				(font
					(size 1.27 1.27)
				)
				(justify mirror)
			)
		)
		(duplicate_pad_numbers_are_jumpers no)
		(fp_line
			(start 0.7874 -0.4064)
			(end -0.7874 -0.4064)
			(stroke
				(width 0.1524)
				(type default)
			)
			(layer "B.SilkS")
		)
		(fp_line
			(start -0.7874 -0.4064)
			(end -0.7874 0.4064)
			(stroke
				(width 0.1524)
				(type default)
			)
			(layer "B.SilkS")
		)
		(fp_line
			(start 0.7874 0.4064)
			(end 0.7874 -0.4064)
			(stroke
				(width 0.1524)
				(type default)
			)
			(layer "B.SilkS")
		)
		(fp_line
			(start -0.7874 0.4064)
			(end 0.7874 0.4064)
			(stroke
				(width 0.1524)
				(type default)
			)
			(layer "B.SilkS")
		)
		(fp_line
			(start 0.67945 -0.305054)
			(end 0.12065 -0.305054)
			(stroke
				(width 0.1)
				(type default)
			)
			(layer "B.Fab")
		)
		(fp_line
			(start 0.12065 -0.305054)
			(end 0.12065 -0.2794)
			(stroke
				(width 0.1)
				(type default)
			)
			(layer "B.Fab")
		)
		(fp_line
			(start -0.12065 -0.3048)
			(end -0.67945 -0.3048)
			(stroke
				(width 0.1)
				(type default)
			)
			(layer "B.Fab")
		)
		(fp_line
			(start -0.67945 -0.3048)
			(end -0.67945 0.3048)
			(stroke
				(width 0.1)
				(type default)
			)
			(layer "B.Fab")
		)
		(fp_line
			(start 0.12065 -0.2794)
			(end -0.12065 -0.2794)
			(stroke
				(width 0.1)
				(type default)
			)
			(layer "B.Fab")
		)
		(fp_line
			(start -0.12065 -0.2794)
			(end -0.12065 -0.3048)
			(stroke
				(width 0.1)
				(type default)
			)
			(layer "B.Fab")
		)
		(fp_line
			(start 0.12065 0.2794)
			(end 0.12065 0.3048)
			(stroke
				(width 0.1)
				(type default)
			)
			(layer "B.Fab")
		)
		(fp_line
			(start -0.120396 0.2794)
			(end 0.12065 0.2794)
			(stroke
				(width 0.1)
				(type default)
			)
			(layer "B.Fab")
		)
		(fp_line
			(start 0.67945 0.3048)
			(end 0.67945 -0.305054)
			(stroke
				(width 0.1)
				(type default)
			)
			(layer "B.Fab")
		)
		(fp_line
			(start 0.12065 0.3048)
			(end 0.67945 0.3048)
			(stroke
				(width 0.1)
				(type default)
			)
			(layer "B.Fab")
		)
		(fp_line
			(start -0.120396 0.3048)
			(end -0.120396 0.2794)
			(stroke
				(width 0.1)
				(type default)
			)
			(layer "B.Fab")
		)
		(fp_line
			(start -0.67945 0.3048)
			(end -0.120396 0.3048)
			(stroke
				(width 0.1)
				(type default)
			)
			(layer "B.Fab")
		)
		(pad "1" smd circle
			(at 0.40005 0 270)
			(size 0 0)
			(layers "B.Cu" "B.Mask" "B.Paste")
			(net "SPI_PEX3_SDIO3_R")
		)
		(pad "2" smd circle
			(at -0.40005 0 270)
			(size 0 0)
			(layers "B.Cu" "B.Mask" "B.Paste")
			(net "SPI_PEX3_SDIO3_R1")
		)
	)
	(footprint ""
		(layer "B.Cu")
		(at 57.749948 -303.499774 -90)
		(property "Reference" "C2917"
			(at 0 0 90)
			(layer "B.SilkS")
			(hide yes)
			(effects
				(font
					(size 1.27 1.27)
				)
				(justify mirror)
			)
		)
		(property "Value" ""
			(at 0 0 90)
			(layer "B.Fab")
			(effects
				(font
					(size 1.27 1.27)
				)
				(justify mirror)
			)
		)
		(duplicate_pad_numbers_are_jumpers no)
		(fp_line
			(start -0.299974 0.150114)
			(end 0.299974 0.150114)
			(stroke
				(width 0.1)
				(type default)
			)
			(layer "B.Fab")
		)
		(fp_line
			(start 0.299974 0.150114)
			(end 0.299974 -0.150114)
			(stroke
				(width 0.1)
				(type default)
			)
			(layer "B.Fab")
		)
		(fp_line
			(start -0.299974 -0.150114)
			(end -0.299974 0.150114)
			(stroke
				(width 0.1)
				(type default)
			)
			(layer "B.Fab")
		)
		(fp_line
			(start 0.299974 -0.150114)
			(end -0.299974 -0.150114)
			(stroke
				(width 0.1)
				(type default)
			)
			(layer "B.Fab")
		)
		(pad "1" smd rect
			(at 0.2667 0 90)
			(size 0.3048 0.381)
			(layers "B.Cu" "B.Mask" "B.Paste")
			(net "P1V25_PEX0")
		)
		(pad "2" smd rect
			(at -0.2667 0 90)
			(size 0.3048 0.381)
			(layers "B.Cu" "B.Mask" "B.Paste")
			(net "GND")
		)
	)
	(footprint ""
		(layer "B.Cu")
		(at 130.539744 -204.209142 180)
		(property "Reference" "R919"
			(at 0 0 0)
			(layer "B.SilkS")
			(hide yes)
			(effects
				(font
					(size 1.27 1.27)
				)
				(justify mirror)
			)
		)
		(property "Value" ""
			(at 0 0 0)
			(layer "B.Fab")
			(effects
				(font
					(size 1.27 1.27)
				)
				(justify mirror)
			)
		)
		(duplicate_pad_numbers_are_jumpers no)
		(fp_line
			(start 0.7874 0.4064)
			(end 0.7874 -0.4064)
			(stroke
				(width 0.1524)
				(type default)
			)
			(layer "B.SilkS")
		)
		(fp_line
			(start 0.7874 -0.4064)
			(end -0.7874 -0.4064)
			(stroke
				(width 0.1524)
				(type default)
			)
			(layer "B.SilkS")
		)
		(fp_line
			(start -0.7874 0.4064)
			(end 0.7874 0.4064)
			(stroke
				(width 0.1524)
				(type default)
			)
			(layer "B.SilkS")
		)
		(fp_line
			(start -0.7874 -0.4064)
			(end -0.7874 0.4064)
			(stroke
				(width 0.1524)
				(type default)
			)
			(layer "B.SilkS")
		)
		(fp_line
			(start 0.67945 0.3048)
			(end 0.67945 -0.305054)
			(stroke
				(width 0.1)
				(type default)
			)
			(layer "B.Fab")
		)
		(fp_line
			(start 0.67945 -0.305054)
			(end 0.12065 -0.305054)
			(stroke
				(width 0.1)
				(type default)
			)
			(layer "B.Fab")
		)
		(fp_line
			(start 0.12065 0.3048)
			(end 0.67945 0.3048)
			(stroke
				(width 0.1)
				(type default)
			)
			(layer "B.Fab")
		)
		(fp_line
			(start 0.12065 0.2794)
			(end 0.12065 0.3048)
			(stroke
				(width 0.1)
				(type default)
			)
			(layer "B.Fab")
		)
		(fp_line
			(start 0.12065 -0.2794)
			(end -0.12065 -0.2794)
			(stroke
				(width 0.1)
				(type default)
			)
			(layer "B.Fab")
		)
		(fp_line
			(start 0.12065 -0.305054)
			(end 0.12065 -0.2794)
			(stroke
				(width 0.1)
				(type default)
			)
			(layer "B.Fab")
		)
		(fp_line
			(start -0.120396 0.3048)
			(end -0.120396 0.2794)
			(stroke
				(width 0.1)
				(type default)
			)
			(layer "B.Fab")
		)
		(fp_line
			(start -0.120396 0.2794)
			(end 0.12065 0.2794)
			(stroke
				(width 0.1)
				(type default)
			)
			(layer "B.Fab")
		)
		(fp_line
			(start -0.12065 -0.2794)
			(end -0.12065 -0.3048)
			(stroke
				(width 0.1)
				(type default)
			)
			(layer "B.Fab")
		)
		(fp_line
			(start -0.12065 -0.3048)
			(end -0.67945 -0.3048)
			(stroke
				(width 0.1)
				(type default)
			)
			(layer "B.Fab")
		)
		(fp_line
			(start -0.67945 0.3048)
			(end -0.120396 0.3048)
			(stroke
				(width 0.1)
				(type default)
			)
			(layer "B.Fab")
		)
		(fp_line
			(start -0.67945 -0.3048)
			(end -0.67945 0.3048)
			(stroke
				(width 0.1)
				(type default)
			)
			(layer "B.Fab")
		)
		(pad "1" smd circle
			(at 0.40005 0)
			(size 0 0)
			(layers "B.Cu" "B.Mask" "B.Paste")
			(net "FT4232_CLI_EEPROM_R_CS")
		)
		(pad "2" smd circle
			(at -0.40005 0)
			(size 0 0)
			(layers "B.Cu" "B.Mask" "B.Paste")
			(net "P3V3_AUX")
		)
	)
	(footprint ""
		(layer "B.Cu")
		(at 117.265958 -321.396106 -90)
		(property "Reference" "R6449"
			(at 0 0 90)
			(layer "B.SilkS")
			(hide yes)
			(effects
				(font
					(size 1.27 1.27)
				)
				(justify mirror)
			)
		)
		(property "Value" ""
			(at 0 0 90)
			(layer "B.Fab")
			(effects
				(font
					(size 1.27 1.27)
				)
				(justify mirror)
			)
		)
		(duplicate_pad_numbers_are_jumpers no)
		(fp_line
			(start -0.7874 0.4064)
			(end 0.7874 0.4064)
			(stroke
				(width 0.1524)
				(type default)
			)
			(layer "B.SilkS")
		)
		(fp_line
			(start 0.7874 0.4064)
			(end 0.7874 -0.4064)
			(stroke
				(width 0.1524)
				(type default)
			)
			(layer "B.SilkS")
		)
		(fp_line
			(start -0.7874 -0.4064)
			(end -0.7874 0.4064)
			(stroke
				(width 0.1524)
				(type default)
			)
			(layer "B.SilkS")
		)
		(fp_line
			(start 0.7874 -0.4064)
			(end -0.7874 -0.4064)
			(stroke
				(width 0.1524)
				(type default)
			)
			(layer "B.SilkS")
		)
		(fp_line
			(start -0.67945 0.3048)
			(end -0.120396 0.3048)
			(stroke
				(width 0.1)
				(type default)
			)
			(layer "B.Fab")
		)
		(fp_line
			(start -0.120396 0.3048)
			(end -0.120396 0.2794)
			(stroke
				(width 0.1)
				(type default)
			)
			(layer "B.Fab")
		)
		(fp_line
			(start 0.12065 0.3048)
			(end 0.67945 0.3048)
			(stroke
				(width 0.1)
				(type default)
			)
			(layer "B.Fab")
		)
		(fp_line
			(start 0.67945 0.3048)
			(end 0.67945 -0.305054)
			(stroke
				(width 0.1)
				(type default)
			)
			(layer "B.Fab")
		)
		(fp_line
			(start -0.120396 0.2794)
			(end 0.12065 0.2794)
			(stroke
				(width 0.1)
				(type default)
			)
			(layer "B.Fab")
		)
		(fp_line
			(start 0.12065 0.2794)
			(end 0.12065 0.3048)
			(stroke
				(width 0.1)
				(type default)
			)
			(layer "B.Fab")
		)
		(fp_line
			(start -0.12065 -0.2794)
			(end -0.12065 -0.3048)
			(stroke
				(width 0.1)
				(type default)
			)
			(layer "B.Fab")
		)
		(fp_line
			(start 0.12065 -0.2794)
			(end -0.12065 -0.2794)
			(stroke
				(width 0.1)
				(type default)
			)
			(layer "B.Fab")
		)
		(fp_line
			(start -0.67945 -0.3048)
			(end -0.67945 0.3048)
			(stroke
				(width 0.1)
				(type default)
			)
			(layer "B.Fab")
		)
		(fp_line
			(start -0.12065 -0.3048)
			(end -0.67945 -0.3048)
			(stroke
				(width 0.1)
				(type default)
			)
			(layer "B.Fab")
		)
		(fp_line
			(start 0.12065 -0.305054)
			(end 0.12065 -0.2794)
			(stroke
				(width 0.1)
				(type default)
			)
			(layer "B.Fab")
		)
		(fp_line
			(start 0.67945 -0.305054)
			(end 0.12065 -0.305054)
			(stroke
				(width 0.1)
				(type default)
			)
			(layer "B.Fab")
		)
		(pad "1" smd circle
			(at 0.40005 0 90)
			(size 0 0)
			(layers "B.Cu" "B.Mask" "B.Paste")
			(net "P0V8_SERDES_VDDA_PEX0")
		)
		(pad "2" smd circle
			(at -0.40005 0 90)
			(size 0 0)
			(layers "B.Cu" "B.Mask" "B.Paste")
			(net "P0V8_SERDES_VDDA_PEX0_C0")
		)
	)
)
